(kicad_pcb
	(version 20260206)
	(generator "pcbnew")
	(generator_version "10.0")
	(general
		(thickness 1.6)
		(legacy_teardrops no)
	)
	(paper "A4")
	(title_block
		(title "v2-pdb — ms_pdb_v2.brd")
		(comment 1 "Open CloudServer (Microsoft) / footprints 191-198 of 348")
	)
	(layers
		(0 "F.Cu" signal "TOP")
		(4 "In1.Cu" signal "GND")
		(6 "In2.Cu" signal "IN1")
		(8 "In3.Cu" signal "VCC")
		(10 "In4.Cu" signal "VCC1")
		(12 "In5.Cu" signal "IN2")
		(14 "In6.Cu" signal "GND1")
		(2 "B.Cu" signal "BOTTOM")
		(9 "F.Adhes" user "F.Adhesive")
		(11 "B.Adhes" user "B.Adhesive")
		(13 "F.Paste" user "Package Geometry/Pastemask Top")
		(15 "B.Paste" user "Package Geometry/Pastemask Bottom")
		(5 "F.SilkS" user "Ref Des/Silkscreen Top")
		(7 "B.SilkS" user "Ref Des/Silkscreen Bottom")
		(1 "F.Mask" user "Board Geometry/Soldermask Top")
		(3 "B.Mask" user "Board Geometry/Soldermask Bottom")
		(17 "Dwgs.User" user "User.Drawings")
		(19 "Cmts.User" user "User.Comments")
		(21 "Eco1.User" user "User.Eco1")
		(23 "Eco2.User" user "User.Eco2")
		(25 "Edge.Cuts" user "Board Geometry/Outline")
		(27 "Margin" user)
		(31 "F.CrtYd" user "Package Geometry/Place Bound Top")
		(29 "B.CrtYd" user "Package Geometry/Place Bound Bottom")
		(35 "F.Fab" user "Ref Des/Assembly Top")
		(33 "B.Fab" user "Ref Des/Assembly Bottom")
	)
	(footprint ""
		(layer "F.Cu")
		(at 91.399868 -375.61012)
		(property "Reference" "H23"
			(at -5.1308 -5.23113 0)
			(unlocked yes)
			(layer "F.SilkS")
			(effects
				(font
					(size 0.7874 0.5842)
					(thickness 0.1524)
				)
				(justify left)
			)
		)
		(property "Value" ""
			(at 0 0 0)
			(layer "F.Fab")
			(effects
				(font
					(size 1.27 1.27)
				)
			)
		)
		(duplicate_pad_numbers_are_jumpers no)
		(fp_circle
			(center 0 0)
			(end 4.826 0)
			(stroke
				(width 0.1524)
				(type default)
			)
			(fill no)
			(layer "F.SilkS")
		)
		(fp_circle
			(center 0 0)
			(end 4.826 0)
			(stroke
				(width 0.1524)
				(type default)
			)
			(fill no)
			(layer "B.SilkS")
		)
		(fp_poly
			(pts
				(arc
					(start 0 4.0132)
					(mid 0 -4.0132)
					(end 0 4.0132)
				)
			)
			(stroke
				(width 0)
				(type default)
			)
			(fill no)
			(layer "F.CrtYd")
		)
		(pad "" np_thru_hole circle
			(at 0 0)
			(size 8.001 8.001)
			(drill 8.001)
			(layers "*.Cu" "*.Mask")
			(clearance 0.381)
			(thermal_gap 0.381)
		)
		(zone
			(layers "F.Cu" "B.Cu" "In1.Cu" "In2.Cu" "In3.Cu" "In4.Cu" "In5.Cu" "In6.Cu")
			(hatch none 0.5)
			(connect_pads
				(clearance 0)
			)
			(min_thickness 0.25)
			(keepout
				(tracks not_allowed)
				(vias allowed)
				(pads allowed)
				(copperpour not_allowed)
				(footprints allowed)
			)
			(placement
				(enabled no)
				(sheetname "")
			)
			(fill
				(thermal_gap 0.5)
				(thermal_bridge_width 0.5)
				(island_removal_mode 0)
			)
			(polygon
				(pts
					(arc
						(start 91.399868 -371.08892)
						(mid 91.399868 -380.13132)
						(end 91.399868 -371.08892)
					)
				)
			)
		)
	)
	(footprint ""
		(layer "F.Cu")
		(at 39.577264 -375.589546 90)
		(property "Reference" "R126"
			(at -0.735076 2.494026 0)
			(unlocked yes)
			(layer "F.SilkS")
			(effects
				(font
					(size 0.7874 0.5842)
					(thickness 0.1524)
				)
				(justify left)
			)
		)
		(property "Value" ""
			(at 0 0 90)
			(layer "F.Fab")
			(effects
				(font
					(size 1.27 1.27)
				)
			)
		)
		(duplicate_pad_numbers_are_jumpers no)
		(fp_line
			(start 0.7874 -0.4064)
			(end 0.7874 0.4064)
			(stroke
				(width 0.1524)
				(type default)
			)
			(layer "F.SilkS")
		)
		(fp_line
			(start -0.7874 -0.4064)
			(end 0.7874 -0.4064)
			(stroke
				(width 0.1524)
				(type default)
			)
			(layer "F.SilkS")
		)
		(fp_line
			(start 0.7874 0.4064)
			(end -0.7874 0.4064)
			(stroke
				(width 0.1524)
				(type default)
			)
			(layer "F.SilkS")
		)
		(fp_line
			(start -0.7874 0.4064)
			(end -0.7874 -0.4064)
			(stroke
				(width 0.1524)
				(type default)
			)
			(layer "F.SilkS")
		)
		(fp_poly
			(pts
				(xy -0.508 0.2794) (xy -0.508 0.2286) (xy -0.635 0.2286) (xy -0.635 -0.254) (xy -0.5334 -0.254)
				(xy -0.5334 -0.2794) (xy 0.5334 -0.2794) (xy 0.5334 -0.254) (xy 0.635 -0.254) (xy 0.635 0.254) (xy 0.5334 0.254)
				(xy 0.5334 0.2794)
			)
			(stroke
				(width 0)
				(type default)
			)
			(fill no)
			(layer "F.CrtYd")
		)
		(pad "1" smd rect
			(at 0.40005 0 90)
			(size 0.4572 0.508)
			(layers "F.Cu" "F.Mask" "F.Paste")
			(net "PSU5_REMOTE_P")
		)
		(pad "2" smd rect
			(at -0.40005 0 90)
			(size 0.4572 0.508)
			(layers "F.Cu" "F.Mask" "F.Paste")
			(net "PSU5_REMOTE_R2_P")
		)
	)
	(footprint ""
		(layer "F.Cu")
		(at 21.441918 -446.145158 90)
		(property "Reference" "R156"
			(at -8.594852 1.446022 90)
			(unlocked yes)
			(layer "F.SilkS")
			(effects
				(font
					(size 0.7874 0.5842)
					(thickness 0.1524)
				)
				(justify left)
			)
		)
		(property "Value" ""
			(at 0 0 90)
			(layer "F.Fab")
			(effects
				(font
					(size 1.27 1.27)
				)
			)
		)
		(duplicate_pad_numbers_are_jumpers no)
		(fp_line
			(start 0.7874 -0.4064)
			(end 0.7874 0.4064)
			(stroke
				(width 0.1524)
				(type default)
			)
			(layer "F.SilkS")
		)
		(fp_line
			(start -0.7874 -0.4064)
			(end 0.7874 -0.4064)
			(stroke
				(width 0.1524)
				(type default)
			)
			(layer "F.SilkS")
		)
		(fp_line
			(start 0.7874 0.4064)
			(end -0.7874 0.4064)
			(stroke
				(width 0.1524)
				(type default)
			)
			(layer "F.SilkS")
		)
		(fp_line
			(start -0.7874 0.4064)
			(end -0.7874 -0.4064)
			(stroke
				(width 0.1524)
				(type default)
			)
			(layer "F.SilkS")
		)
		(fp_poly
			(pts
				(xy -0.508 0.2794) (xy -0.508 0.2286) (xy -0.635 0.2286) (xy -0.635 -0.254) (xy -0.5334 -0.254)
				(xy -0.5334 -0.2794) (xy 0.5334 -0.2794) (xy 0.5334 -0.254) (xy 0.635 -0.254) (xy 0.635 0.254) (xy 0.5334 0.254)
				(xy 0.5334 0.2794)
			)
			(stroke
				(width 0)
				(type default)
			)
			(fill no)
			(layer "F.CrtYd")
		)
		(pad "1" smd rect
			(at 0.40005 0 90)
			(size 0.4572 0.508)
			(layers "F.Cu" "F.Mask" "F.Paste")
			(net "P3V3_BUF")
		)
		(pad "2" smd rect
			(at -0.40005 0 90)
			(size 0.4572 0.508)
			(layers "F.Cu" "F.Mask" "F.Paste")
			(net "N42242090")
		)
	)
	(footprint ""
		(layer "F.Cu")
		(at 73.45934 -330.332588 -90)
		(property "Reference" "C51"
			(at 3.323336 -0.07366 90)
			(unlocked yes)
			(layer "F.SilkS")
			(effects
				(font
					(size 0.7874 0.5842)
					(thickness 0.1524)
				)
				(justify left)
			)
		)
		(property "Value" ""
			(at 0 0 270)
			(layer "F.Fab")
			(effects
				(font
					(size 1.27 1.27)
				)
			)
		)
		(duplicate_pad_numbers_are_jumpers no)
		(fp_line
			(start -0.7874 0.4064)
			(end -0.7874 -0.4064)
			(stroke
				(width 0.1524)
				(type default)
			)
			(layer "F.SilkS")
		)
		(fp_line
			(start 0.7874 0.4064)
			(end -0.7874 0.4064)
			(stroke
				(width 0.1524)
				(type default)
			)
			(layer "F.SilkS")
		)
		(fp_line
			(start 0 0.381)
			(end 0 -0.381)
			(stroke
				(width 0.1524)
				(type default)
			)
			(layer "F.SilkS")
		)
		(fp_line
			(start -0.7874 -0.4064)
			(end 0.7874 -0.4064)
			(stroke
				(width 0.1524)
				(type default)
			)
			(layer "F.SilkS")
		)
		(fp_line
			(start 0.7874 -0.4064)
			(end 0.7874 0.4064)
			(stroke
				(width 0.1524)
				(type default)
			)
			(layer "F.SilkS")
		)
		(fp_poly
			(pts
				(xy -0.5334 0.254) (xy -0.635 0.254) (xy -0.635 0.2286) (xy -0.635 -0.254) (xy -0.5334 -0.254) (xy -0.5334 -0.2794)
				(xy 0.5334 -0.2794) (xy 0.5334 -0.254) (xy 0.635 -0.254) (xy 0.635 0.254) (xy 0.5334 0.254) (xy 0.5334 0.2794)
				(xy -0.508 0.2794) (xy -0.5334 0.2794)
			)
			(stroke
				(width 0)
				(type default)
			)
			(fill no)
			(layer "F.CrtYd")
		)
		(pad "1" smd rect
			(at 0.40005 0 270)
			(size 0.4572 0.508)
			(layers "F.Cu" "F.Mask" "F.Paste")
			(net "P12V")
		)
		(pad "2" smd rect
			(at -0.40005 0 270)
			(size 0.4572 0.508)
			(layers "F.Cu" "F.Mask" "F.Paste")
			(net "GND")
		)
	)
	(footprint ""
		(layer "F.Cu")
		(at 72.928734 -483.48138 90)
		(property "Reference" "C81"
			(at -4.217416 0.323088 90)
			(unlocked yes)
			(layer "F.SilkS")
			(effects
				(font
					(size 0.7874 0.5842)
					(thickness 0.1524)
				)
				(justify left)
			)
		)
		(property "Value" ""
			(at 0 0 90)
			(layer "F.Fab")
			(effects
				(font
					(size 1.27 1.27)
				)
			)
		)
		(duplicate_pad_numbers_are_jumpers no)
		(fp_line
			(start 0.7874 -0.4064)
			(end 0.7874 0.4064)
			(stroke
				(width 0.1524)
				(type default)
			)
			(layer "F.SilkS")
		)
		(fp_line
			(start -0.7874 -0.4064)
			(end 0.7874 -0.4064)
			(stroke
				(width 0.1524)
				(type default)
			)
			(layer "F.SilkS")
		)
		(fp_line
			(start 0 0.381)
			(end 0 -0.381)
			(stroke
				(width 0.1524)
				(type default)
			)
			(layer "F.SilkS")
		)
		(fp_line
			(start 0.7874 0.4064)
			(end -0.7874 0.4064)
			(stroke
				(width 0.1524)
				(type default)
			)
			(layer "F.SilkS")
		)
		(fp_line
			(start -0.7874 0.4064)
			(end -0.7874 -0.4064)
			(stroke
				(width 0.1524)
				(type default)
			)
			(layer "F.SilkS")
		)
		(fp_poly
			(pts
				(xy -0.5334 0.254) (xy -0.635 0.254) (xy -0.635 0.2286) (xy -0.635 -0.254) (xy -0.5334 -0.254) (xy -0.5334 -0.2794)
				(xy 0.5334 -0.2794) (xy 0.5334 -0.254) (xy 0.635 -0.254) (xy 0.635 0.254) (xy 0.5334 0.254) (xy 0.5334 0.2794)
				(xy -0.508 0.2794) (xy -0.5334 0.2794)
			)
			(stroke
				(width 0)
				(type default)
			)
			(fill no)
			(layer "F.CrtYd")
		)
		(pad "1" smd rect
			(at 0.40005 0 90)
			(size 0.4572 0.508)
			(layers "F.Cu" "F.Mask" "F.Paste")
			(net "P12V")
		)
		(pad "2" smd rect
			(at -0.40005 0 90)
			(size 0.4572 0.508)
			(layers "F.Cu" "F.Mask" "F.Paste")
			(net "GND")
		)
	)
	(footprint ""
		(layer "F.Cu")
		(at 71.390764 -464.050634 -90)
		(property "Reference" "C71"
			(at -3.412236 0.548894 90)
			(unlocked yes)
			(layer "F.SilkS")
			(effects
				(font
					(size 0.7874 0.5842)
					(thickness 0.1524)
				)
			)
		)
		(property "Value" ""
			(at 0 0 270)
			(layer "F.Fab")
			(effects
				(font
					(size 1.27 1.27)
				)
			)
		)
		(duplicate_pad_numbers_are_jumpers no)
		(fp_line
			(start -1.2954 0.5842)
			(end -1.2954 -0.5842)
			(stroke
				(width 0.1524)
				(type default)
			)
			(layer "F.SilkS")
		)
		(fp_line
			(start 1.2954 0.5842)
			(end -1.2954 0.5842)
			(stroke
				(width 0.1524)
				(type default)
			)
			(layer "F.SilkS")
		)
		(fp_line
			(start -1.2954 -0.5842)
			(end 1.2954 -0.5842)
			(stroke
				(width 0.1524)
				(type default)
			)
			(layer "F.SilkS")
		)
		(fp_line
			(start 0 -0.5842)
			(end 0 0.5842)
			(stroke
				(width 0.1524)
				(type default)
			)
			(layer "F.SilkS")
		)
		(fp_line
			(start 1.2954 -0.5842)
			(end 1.2954 0.5842)
			(stroke
				(width 0.1524)
				(type default)
			)
			(layer "F.SilkS")
		)
		(fp_poly
			(pts
				(xy 0.8636 -0.4572) (xy 0.8636 -0.3556) (xy 1.143 -0.3556) (xy 1.143 0.3556) (xy 0.8636 0.3556)
				(xy 0.8636 0.4572) (xy -0.8636 0.4572) (xy -0.8636 0.3556) (xy -1.143 0.3556) (xy -1.143 -0.3556)
				(xy -0.8636 -0.3556) (xy -0.8636 -0.4572)
			)
			(stroke
				(width 0)
				(type default)
			)
			(fill no)
			(layer "F.CrtYd")
		)
		(fp_line
			(start -0.884936 0.504952)
			(end -0.884936 -0.504952)
			(stroke
				(width 0.1)
				(type default)
			)
			(layer "F.Fab")
		)
		(fp_line
			(start 0.884936 0.504952)
			(end -0.884936 0.504952)
			(stroke
				(width 0.1)
				(type default)
			)
			(layer "F.Fab")
		)
		(fp_line
			(start -0.884936 -0.504952)
			(end 0.884936 -0.504952)
			(stroke
				(width 0.1)
				(type default)
			)
			(layer "F.Fab")
		)
		(fp_line
			(start 0.884936 -0.504952)
			(end 0.884936 0.504952)
			(stroke
				(width 0.1)
				(type default)
			)
			(layer "F.Fab")
		)
		(pad "1" smd rect
			(at 0.7366 0)
			(size 0.7112 0.8128)
			(layers "F.Cu" "F.Mask" "F.Paste")
			(net "P12V")
		)
		(pad "2" smd rect
			(at -0.7366 0)
			(size 0.7112 0.8128)
			(layers "F.Cu" "F.Mask" "F.Paste")
			(net "GND")
		)
	)
	(footprint ""
		(layer "F.Cu")
		(at 13.319506 -229.665784 180)
		(property "Reference" "R163"
			(at 0.625856 -1.451102 0)
			(unlocked yes)
			(layer "F.SilkS")
			(effects
				(font
					(size 0.7874 0.5842)
					(thickness 0.1524)
				)
				(justify left)
			)
		)
		(property "Value" ""
			(at 0 0 180)
			(layer "F.Fab")
			(effects
				(font
					(size 1.27 1.27)
				)
			)
		)
		(duplicate_pad_numbers_are_jumpers no)
		(fp_line
			(start 0.7874 0.4064)
			(end -0.7874 0.4064)
			(stroke
				(width 0.1524)
				(type default)
			)
			(layer "F.SilkS")
		)
		(fp_line
			(start 0.7874 -0.4064)
			(end 0.7874 0.4064)
			(stroke
				(width 0.1524)
				(type default)
			)
			(layer "F.SilkS")
		)
		(fp_line
			(start -0.7874 0.4064)
			(end -0.7874 -0.4064)
			(stroke
				(width 0.1524)
				(type default)
			)
			(layer "F.SilkS")
		)
		(fp_line
			(start -0.7874 -0.4064)
			(end 0.7874 -0.4064)
			(stroke
				(width 0.1524)
				(type default)
			)
			(layer "F.SilkS")
		)
		(fp_poly
			(pts
				(xy -0.508 0.2794) (xy -0.508 0.2286) (xy -0.635 0.2286) (xy -0.635 -0.254) (xy -0.5334 -0.254)
				(xy -0.5334 -0.2794) (xy 0.5334 -0.2794) (xy 0.5334 -0.254) (xy 0.635 -0.254) (xy 0.635 0.254) (xy 0.5334 0.254)
				(xy 0.5334 0.2794)
			)
			(stroke
				(width 0)
				(type default)
			)
			(fill no)
			(layer "F.CrtYd")
		)
		(pad "1" smd rect
			(at 0.40005 0 180)
			(size 0.4572 0.508)
			(layers "F.Cu" "F.Mask" "F.Paste")
			(net "T1_BLAD2_EN")
		)
		(pad "2" smd rect
			(at -0.40005 0 180)
			(size 0.4572 0.508)
			(layers "F.Cu" "F.Mask" "F.Paste")
			(net "PSU_ALERT_N")
		)
	)
	(footprint ""
		(layer "F.Cu")
		(at 70.260718 -63.973456 -90)
		(property "Reference" "C9"
			(at -2.559304 0.19939 90)
			(unlocked yes)
			(layer "F.SilkS")
			(effects
				(font
					(size 0.7874 0.5842)
					(thickness 0.1524)
				)
				(justify left)
			)
		)
		(property "Value" ""
			(at 0 0 270)
			(layer "F.Fab")
			(effects
				(font
					(size 1.27 1.27)
				)
			)
		)
		(duplicate_pad_numbers_are_jumpers no)
		(fp_line
			(start -0.7874 0.4064)
			(end -0.7874 -0.4064)
			(stroke
				(width 0.1524)
				(type default)
			)
			(layer "F.SilkS")
		)
		(fp_line
			(start 0.7874 0.4064)
			(end -0.7874 0.4064)
			(stroke
				(width 0.1524)
				(type default)
			)
			(layer "F.SilkS")
		)
		(fp_line
			(start 0 0.381)
			(end 0 -0.381)
			(stroke
				(width 0.1524)
				(type default)
			)
			(layer "F.SilkS")
		)
		(fp_line
			(start -0.7874 -0.4064)
			(end 0.7874 -0.4064)
			(stroke
				(width 0.1524)
				(type default)
			)
			(layer "F.SilkS")
		)
		(fp_line
			(start 0.7874 -0.4064)
			(end 0.7874 0.4064)
			(stroke
				(width 0.1524)
				(type default)
			)
			(layer "F.SilkS")
		)
		(fp_poly
			(pts
				(xy -0.5334 0.254) (xy -0.635 0.254) (xy -0.635 0.2286) (xy -0.635 -0.254) (xy -0.5334 -0.254) (xy -0.5334 -0.2794)
				(xy 0.5334 -0.2794) (xy 0.5334 -0.254) (xy 0.635 -0.254) (xy 0.635 0.254) (xy 0.5334 0.254) (xy 0.5334 0.2794)
				(xy -0.508 0.2794) (xy -0.5334 0.2794)
			)
			(stroke
				(width 0)
				(type default)
			)
			(fill no)
			(layer "F.CrtYd")
		)
		(pad "1" smd rect
			(at 0.40005 0 270)
			(size 0.4572 0.508)
			(layers "F.Cu" "F.Mask" "F.Paste")
			(net "P12V")
		)
		(pad "2" smd rect
			(at -0.40005 0 270)
			(size 0.4572 0.508)
			(layers "F.Cu" "F.Mask" "F.Paste")
			(net "GND")
		)
	)
)
